# S9S_MB_2U (Grand Teton) — schematic netlist excerpt (pin names and nets, part order shuffled) for the footprints in the layout excerpt that follows; sources: Cadence DE-HDL packaged netlist, KiCad conversion of 03242023_DA0F0TMBIJ0_F0T_Motherboard_J_brd_V01_OCP.brd

C361  Q_CAP  47UF 4V 20% X6S  pkg C0805  page 75 : A = PVCCIN_CPU0 ; B = GND
C347  Q_CAP  47UF 4V 20% X6S  pkg C0805  page 79 : A = PVCCIN_CPU1 ; B = GND
R4290  Q_RES  4.7K 1% EMPTY  pkg 0402LF  page 169 : A = FM_USB3_1_RXDET_EN ; B = GND

(kicad_pcb
	(version 20260206)
	(generator "pcbnew")
	(generator_version "10.0")
	(general
		(thickness 1.6)
		(legacy_teardrops no)
	)
	(paper "A4")
	(title_block
		(title "03242023_DA0F0TMBIJ0_F0T_Motherboard_J_brd_V01_OCP.brd")
		(comment 1 "Grand Teton / footprints 4695-4697 of 6105")
	)
	(layers
		(0 "F.Cu" signal "TOP")
		(4 "In1.Cu" signal "GND")
		(6 "In2.Cu" signal "IN1")
		(8 "In3.Cu" signal "GND1")
		(10 "In4.Cu" signal "IN2")
		(12 "In5.Cu" signal "GND2")
		(14 "In6.Cu" signal "IN3")
		(16 "In7.Cu" signal "GND3")
		(18 "In8.Cu" signal "VCC")
		(20 "In9.Cu" signal "VCC1")
		(22 "In10.Cu" signal "GND4")
		(24 "In11.Cu" signal "IN4")
		(26 "In12.Cu" signal "GND5")
		(28 "In13.Cu" signal "IN5")
		(30 "In14.Cu" signal "GND6")
		(32 "In15.Cu" signal "IN6")
		(34 "In16.Cu" signal "GND7")
		(2 "B.Cu" signal "BOTTOM")
		(9 "F.Adhes" user "F.Adhesive")
		(11 "B.Adhes" user "B.Adhesive")
		(13 "F.Paste" user "Package Geometry/Pastemask Top")
		(15 "B.Paste" user "Package Geometry/Pastemask Bottom")
		(5 "F.SilkS" user "Ref Des/Silkscreen Top")
		(7 "B.SilkS" user "Ref Des/Silkscreen Bottom")
		(1 "F.Mask" user "Board Geometry/Soldermask Top")
		(3 "B.Mask" user "Board Geometry/Soldermask Bottom")
		(17 "Dwgs.User" user "User.Drawings")
		(19 "Cmts.User" user "User.Comments")
		(21 "Eco1.User" user "User.Eco1")
		(23 "Eco2.User" user "User.Eco2")
		(25 "Edge.Cuts" user "Board Geometry/Outline")
		(27 "Margin" user)
		(31 "F.CrtYd" user "Package Geometry/Place Bound Top")
		(29 "B.CrtYd" user "Package Geometry/Place Bound Bottom")
		(35 "F.Fab" user "Ref Des/Assembly Top")
		(33 "B.Fab" user "Ref Des/Assembly Bottom")
	)
	(footprint ""
		(layer "B.Cu")
		(at 126.65202 -36.761928 90)
		(property "Reference" "R4290"
			(at 0 0 90)
			(layer "B.SilkS")
			(hide yes)
			(effects
				(font
					(size 1.27 1.27)
				)
				(justify mirror)
			)
		)
		(property "Value" ""
			(at 0 0 90)
			(layer "B.Fab")
			(effects
				(font
					(size 1.27 1.27)
				)
				(justify mirror)
			)
		)
		(duplicate_pad_numbers_are_jumpers no)
		(fp_line
			(start 0.7874 -0.4064)
			(end -0.7874 -0.4064)
			(stroke
				(width 0.1524)
				(type default)
			)
			(layer "B.SilkS")
		)
		(fp_line
			(start -0.7874 -0.4064)
			(end -0.7874 0.4064)
			(stroke
				(width 0.1524)
				(type default)
			)
			(layer "B.SilkS")
		)
		(fp_line
			(start 0.7874 0.4064)
			(end 0.7874 -0.4064)
			(stroke
				(width 0.1524)
				(type default)
			)
			(layer "B.SilkS")
		)
		(fp_line
			(start -0.7874 0.4064)
			(end 0.7874 0.4064)
			(stroke
				(width 0.1524)
				(type default)
			)
			(layer "B.SilkS")
		)
		(fp_line
			(start 0.67945 -0.305054)
			(end 0.12065 -0.305054)
			(stroke
				(width 0.1)
				(type default)
			)
			(layer "B.Fab")
		)
		(fp_line
			(start 0.12065 -0.305054)
			(end 0.12065 -0.2794)
			(stroke
				(width 0.1)
				(type default)
			)
			(layer "B.Fab")
		)
		(fp_line
			(start -0.12065 -0.3048)
			(end -0.67945 -0.3048)
			(stroke
				(width 0.1)
				(type default)
			)
			(layer "B.Fab")
		)
		(fp_line
			(start -0.67945 -0.3048)
			(end -0.67945 0.3048)
			(stroke
				(width 0.1)
				(type default)
			)
			(layer "B.Fab")
		)
		(fp_line
			(start 0.12065 -0.2794)
			(end -0.12065 -0.2794)
			(stroke
				(width 0.1)
				(type default)
			)
			(layer "B.Fab")
		)
		(fp_line
			(start -0.12065 -0.2794)
			(end -0.12065 -0.3048)
			(stroke
				(width 0.1)
				(type default)
			)
			(layer "B.Fab")
		)
		(fp_line
			(start 0.12065 0.2794)
			(end 0.12065 0.3048)
			(stroke
				(width 0.1)
				(type default)
			)
			(layer "B.Fab")
		)
		(fp_line
			(start -0.120396 0.2794)
			(end 0.12065 0.2794)
			(stroke
				(width 0.1)
				(type default)
			)
			(layer "B.Fab")
		)
		(fp_line
			(start 0.67945 0.3048)
			(end 0.67945 -0.305054)
			(stroke
				(width 0.1)
				(type default)
			)
			(layer "B.Fab")
		)
		(fp_line
			(start 0.12065 0.3048)
			(end 0.67945 0.3048)
			(stroke
				(width 0.1)
				(type default)
			)
			(layer "B.Fab")
		)
		(fp_line
			(start -0.120396 0.3048)
			(end -0.120396 0.2794)
			(stroke
				(width 0.1)
				(type default)
			)
			(layer "B.Fab")
		)
		(fp_line
			(start -0.67945 0.3048)
			(end -0.120396 0.3048)
			(stroke
				(width 0.1)
				(type default)
			)
			(layer "B.Fab")
		)
		(pad "1" smd circle
			(at 0.40005 0 270)
			(size 0 0)
			(layers "B.Cu" "B.Mask" "B.Paste")
			(net "FM_USB3_1_RXDET_EN")
		)
		(pad "2" smd circle
			(at -0.40005 0 270)
			(size 0 0)
			(layers "B.Cu" "B.Mask" "B.Paste")
			(net "GND")
		)
	)
	(footprint ""
		(layer "B.Cu")
		(at 121.545604 -294.01008 180)
		(property "Reference" "C347"
			(at 0 0 0)
			(layer "B.SilkS")
			(hide yes)
			(effects
				(font
					(size 1.27 1.27)
				)
				(justify mirror)
			)
		)
		(property "Value" ""
			(at 0 0 0)
			(layer "B.Fab")
			(effects
				(font
					(size 1.27 1.27)
				)
				(justify mirror)
			)
		)
		(duplicate_pad_numbers_are_jumpers no)
		(fp_line
			(start 1.524 0.762)
			(end 1.524 -0.762)
			(stroke
				(width 0.1524)
				(type default)
			)
			(layer "B.SilkS")
		)
		(fp_line
			(start 1.524 -0.762)
			(end -1.524 -0.762)
			(stroke
				(width 0.1524)
				(type default)
			)
			(layer "B.SilkS")
		)
		(fp_line
			(start -1.524 0.762)
			(end 1.524 0.762)
			(stroke
				(width 0.1524)
				(type default)
			)
			(layer "B.SilkS")
		)
		(fp_line
			(start -1.524 -0.762)
			(end -1.524 0.762)
			(stroke
				(width 0.1524)
				(type default)
			)
			(layer "B.SilkS")
		)
		(fp_line
			(start 1.1049 0.724916)
			(end -1.1049 0.724916)
			(stroke
				(width 0.1)
				(type default)
			)
			(layer "B.Fab")
		)
		(fp_line
			(start 1.1049 -0.724916)
			(end 1.1049 0.724916)
			(stroke
				(width 0.1)
				(type default)
			)
			(layer "B.Fab")
		)
		(fp_line
			(start -1.1049 0.724916)
			(end -1.1049 -0.724916)
			(stroke
				(width 0.1)
				(type default)
			)
			(layer "B.Fab")
		)
		(fp_line
			(start -1.1049 -0.724916)
			(end 1.1049 -0.724916)
			(stroke
				(width 0.1)
				(type default)
			)
			(layer "B.Fab")
		)
		(pad "1" smd rect
			(at 0.889 0 180)
			(size 1.016 1.27)
			(layers "B.Cu" "B.Mask" "B.Paste")
			(net "PVCCIN_CPU1")
		)
		(pad "2" smd rect
			(at -0.889 0 180)
			(size 1.016 1.27)
			(layers "B.Cu" "B.Mask" "B.Paste")
			(net "GND")
		)
	)
	(footprint ""
		(layer "B.Cu")
		(at 367.898934 -255.853946 -90)
		(property "Reference" "C361"
			(at 0 0 90)
			(layer "B.SilkS")
			(hide yes)
			(effects
				(font
					(size 1.27 1.27)
				)
				(justify mirror)
			)
		)
		(property "Value" ""
			(at 0 0 90)
			(layer "B.Fab")
			(effects
				(font
					(size 1.27 1.27)
				)
				(justify mirror)
			)
		)
		(duplicate_pad_numbers_are_jumpers no)
		(fp_line
			(start -1.524 0.762)
			(end 1.524 0.762)
			(stroke
				(width 0.1524)
				(type default)
			)
			(layer "B.SilkS")
		)
		(fp_line
			(start 1.524 0.762)
			(end 1.524 -0.762)
			(stroke
				(width 0.1524)
				(type default)
			)
			(layer "B.SilkS")
		)
		(fp_line
			(start -1.524 -0.762)
			(end -1.524 0.762)
			(stroke
				(width 0.1524)
				(type default)
			)
			(layer "B.SilkS")
		)
		(fp_line
			(start 1.524 -0.762)
			(end -1.524 -0.762)
			(stroke
				(width 0.1524)
				(type default)
			)
			(layer "B.SilkS")
		)
		(fp_line
			(start -1.1049 0.724916)
			(end -1.1049 -0.724916)
			(stroke
				(width 0.1)
				(type default)
			)
			(layer "B.Fab")
		)
		(fp_line
			(start 1.1049 0.724916)
			(end -1.1049 0.724916)
			(stroke
				(width 0.1)
				(type default)
			)
			(layer "B.Fab")
		)
		(fp_line
			(start -1.1049 -0.724916)
			(end 1.1049 -0.724916)
			(stroke
				(width 0.1)
				(type default)
			)
			(layer "B.Fab")
		)
		(fp_line
			(start 1.1049 -0.724916)
			(end 1.1049 0.724916)
			(stroke
				(width 0.1)
				(type default)
			)
			(layer "B.Fab")
		)
		(pad "1" smd rect
			(at 0.889 0 270)
			(size 1.016 1.27)
			(layers "B.Cu" "B.Mask" "B.Paste")
			(net "PVCCIN_CPU0")
		)
		(pad "2" smd rect
			(at -0.889 0 270)
			(size 1.016 1.27)
			(layers "B.Cu" "B.Mask" "B.Paste")
			(net "GND")
		)
	)
)
